(kicad_pcb
	(version 20260206)
	(generator "pcbnew")
	(generator_version "10.0")
	(general
		(thickness 1.6)
		(legacy_teardrops no)
	)
	(paper "A4")
	(title_block
		(title "01162023_DA0F0TEBIF0_F0T_Expander_BD_F_brd_V02_OCP.brd")
		(comment 1 "Grand Teton / footprints 6137-6143 of 9728")
	)
	(layers
		(0 "F.Cu" signal "TOP")
		(4 "In1.Cu" signal "GND")
		(6 "In2.Cu" signal "VCC")
		(8 "In3.Cu" signal "VCC1")
		(10 "In4.Cu" signal "GND1")
		(12 "In5.Cu" signal "IN1")
		(14 "In6.Cu" signal "GND2")
		(16 "In7.Cu" signal "IN2")
		(18 "In8.Cu" signal "GND3")
		(20 "In9.Cu" signal "IN3")
		(22 "In10.Cu" signal "GND4")
		(24 "In11.Cu" signal "IN4")
		(26 "In12.Cu" signal "GND5")
		(28 "In13.Cu" signal "IN5")
		(30 "In14.Cu" signal "GND6")
		(32 "In15.Cu" signal "IN6")
		(34 "In16.Cu" signal "GND7")
		(2 "B.Cu" signal "BOTTOM")
		(9 "F.Adhes" user "F.Adhesive")
		(11 "B.Adhes" user "B.Adhesive")
		(13 "F.Paste" user "Package Geometry/Pastemask Top")
		(15 "B.Paste" user "Package Geometry/Pastemask Bottom")
		(5 "F.SilkS" user "Ref Des/Silkscreen Top")
		(7 "B.SilkS" user "Ref Des/Silkscreen Bottom")
		(1 "F.Mask" user "Board Geometry/Soldermask Top")
		(3 "B.Mask" user "Board Geometry/Soldermask Bottom")
		(17 "Dwgs.User" user "User.Drawings")
		(19 "Cmts.User" user "User.Comments")
		(21 "Eco1.User" user "User.Eco1")
		(23 "Eco2.User" user "User.Eco2")
		(25 "Edge.Cuts" user "Board Geometry/Outline")
		(27 "Margin" user)
		(31 "F.CrtYd" user "Package Geometry/Place Bound Top")
		(29 "B.CrtYd" user "Package Geometry/Place Bound Bottom")
		(35 "F.Fab" user "Ref Des/Assembly Top")
		(33 "B.Fab" user "Ref Des/Assembly Bottom")
	)
	(footprint ""
		(layer "F.Cu")
		(at 358.792526 -252.045978 180)
		(property "Reference" "R1762"
			(at 0 0 180)
			(layer "F.SilkS")
			(hide yes)
			(effects
				(font
					(size 1.27 1.27)
				)
			)
		)
		(property "Value" ""
			(at 0 0 180)
			(layer "F.Fab")
			(effects
				(font
					(size 1.27 1.27)
				)
			)
		)
		(duplicate_pad_numbers_are_jumpers no)
		(fp_line
			(start 0.7874 0.4064)
			(end -0.7874 0.4064)
			(stroke
				(width 0.1524)
				(type default)
			)
			(layer "F.SilkS")
		)
		(fp_line
			(start 0.7874 -0.4064)
			(end 0.7874 0.4064)
			(stroke
				(width 0.1524)
				(type default)
			)
			(layer "F.SilkS")
		)
		(fp_line
			(start -0.7874 0.4064)
			(end -0.7874 -0.4064)
			(stroke
				(width 0.1524)
				(type default)
			)
			(layer "F.SilkS")
		)
		(fp_line
			(start -0.7874 -0.4064)
			(end 0.7874 -0.4064)
			(stroke
				(width 0.1524)
				(type default)
			)
			(layer "F.SilkS")
		)
		(fp_line
			(start 0.67945 0.3048)
			(end 0.120396 0.3048)
			(stroke
				(width 0.1)
				(type default)
			)
			(layer "F.Fab")
		)
		(fp_line
			(start 0.67945 -0.3048)
			(end 0.67945 0.3048)
			(stroke
				(width 0.1)
				(type default)
			)
			(layer "F.Fab")
		)
		(fp_line
			(start 0.12065 -0.2794)
			(end 0.12065 -0.3048)
			(stroke
				(width 0.1)
				(type default)
			)
			(layer "F.Fab")
		)
		(fp_line
			(start 0.12065 -0.3048)
			(end 0.67945 -0.3048)
			(stroke
				(width 0.1)
				(type default)
			)
			(layer "F.Fab")
		)
		(fp_line
			(start 0.120396 0.3048)
			(end 0.120396 0.2794)
			(stroke
				(width 0.1)
				(type default)
			)
			(layer "F.Fab")
		)
		(fp_line
			(start 0.120396 0.2794)
			(end -0.12065 0.2794)
			(stroke
				(width 0.1)
				(type default)
			)
			(layer "F.Fab")
		)
		(fp_line
			(start -0.12065 0.3048)
			(end -0.67945 0.3048)
			(stroke
				(width 0.1)
				(type default)
			)
			(layer "F.Fab")
		)
		(fp_line
			(start -0.12065 0.2794)
			(end -0.12065 0.3048)
			(stroke
				(width 0.1)
				(type default)
			)
			(layer "F.Fab")
		)
		(fp_line
			(start -0.12065 -0.2794)
			(end 0.12065 -0.2794)
			(stroke
				(width 0.1)
				(type default)
			)
			(layer "F.Fab")
		)
		(fp_line
			(start -0.12065 -0.305054)
			(end -0.12065 -0.2794)
			(stroke
				(width 0.1)
				(type default)
			)
			(layer "F.Fab")
		)
		(fp_line
			(start -0.67945 0.3048)
			(end -0.67945 -0.305054)
			(stroke
				(width 0.1)
				(type default)
			)
			(layer "F.Fab")
		)
		(fp_line
			(start -0.67945 -0.305054)
			(end -0.12065 -0.305054)
			(stroke
				(width 0.1)
				(type default)
			)
			(layer "F.Fab")
		)
		(pad "1" smd circle
			(at -0.40005 0 180)
			(size 0 0)
			(layers "F.Cu" "F.Mask" "F.Paste")
			(net "P3V3_AUX")
		)
		(pad "2" smd circle
			(at 0.40005 0 180)
			(size 0 0)
			(layers "F.Cu" "F.Mask" "F.Paste")
			(net "SMB_BIC_I2C6_MUX_VR_R_SCL")
		)
	)
	(footprint ""
		(layer "F.Cu")
		(at 217.756486 -17.419574 180)
		(property "Reference" "R1677"
			(at 0 0 180)
			(layer "F.SilkS")
			(hide yes)
			(effects
				(font
					(size 1.27 1.27)
				)
			)
		)
		(property "Value" ""
			(at 0 0 180)
			(layer "F.Fab")
			(effects
				(font
					(size 1.27 1.27)
				)
			)
		)
		(duplicate_pad_numbers_are_jumpers no)
		(fp_line
			(start 0.7874 0.4064)
			(end -0.7874 0.4064)
			(stroke
				(width 0.1524)
				(type default)
			)
			(layer "F.SilkS")
		)
		(fp_line
			(start 0.7874 -0.4064)
			(end 0.7874 0.4064)
			(stroke
				(width 0.1524)
				(type default)
			)
			(layer "F.SilkS")
		)
		(fp_line
			(start -0.7874 0.4064)
			(end -0.7874 -0.4064)
			(stroke
				(width 0.1524)
				(type default)
			)
			(layer "F.SilkS")
		)
		(fp_line
			(start -0.7874 -0.4064)
			(end 0.7874 -0.4064)
			(stroke
				(width 0.1524)
				(type default)
			)
			(layer "F.SilkS")
		)
		(fp_line
			(start 0.67945 0.3048)
			(end 0.120396 0.3048)
			(stroke
				(width 0.1)
				(type default)
			)
			(layer "F.Fab")
		)
		(fp_line
			(start 0.67945 -0.3048)
			(end 0.67945 0.3048)
			(stroke
				(width 0.1)
				(type default)
			)
			(layer "F.Fab")
		)
		(fp_line
			(start 0.12065 -0.2794)
			(end 0.12065 -0.3048)
			(stroke
				(width 0.1)
				(type default)
			)
			(layer "F.Fab")
		)
		(fp_line
			(start 0.12065 -0.3048)
			(end 0.67945 -0.3048)
			(stroke
				(width 0.1)
				(type default)
			)
			(layer "F.Fab")
		)
		(fp_line
			(start 0.120396 0.3048)
			(end 0.120396 0.2794)
			(stroke
				(width 0.1)
				(type default)
			)
			(layer "F.Fab")
		)
		(fp_line
			(start 0.120396 0.2794)
			(end -0.12065 0.2794)
			(stroke
				(width 0.1)
				(type default)
			)
			(layer "F.Fab")
		)
		(fp_line
			(start -0.12065 0.3048)
			(end -0.67945 0.3048)
			(stroke
				(width 0.1)
				(type default)
			)
			(layer "F.Fab")
		)
		(fp_line
			(start -0.12065 0.2794)
			(end -0.12065 0.3048)
			(stroke
				(width 0.1)
				(type default)
			)
			(layer "F.Fab")
		)
		(fp_line
			(start -0.12065 -0.2794)
			(end 0.12065 -0.2794)
			(stroke
				(width 0.1)
				(type default)
			)
			(layer "F.Fab")
		)
		(fp_line
			(start -0.12065 -0.305054)
			(end -0.12065 -0.2794)
			(stroke
				(width 0.1)
				(type default)
			)
			(layer "F.Fab")
		)
		(fp_line
			(start -0.67945 0.3048)
			(end -0.67945 -0.305054)
			(stroke
				(width 0.1)
				(type default)
			)
			(layer "F.Fab")
		)
		(fp_line
			(start -0.67945 -0.305054)
			(end -0.12065 -0.305054)
			(stroke
				(width 0.1)
				(type default)
			)
			(layer "F.Fab")
		)
		(pad "1" smd circle
			(at -0.40005 0 180)
			(size 0 0)
			(layers "F.Cu" "F.Mask" "F.Paste")
			(net "P3V3_SSD7")
		)
		(pad "2" smd circle
			(at 0.40005 0 180)
			(size 0 0)
			(layers "F.Cu" "F.Mask" "F.Paste")
			(net "SMB_ISO_SSD7_SCL")
		)
	)
	(footprint ""
		(layer "F.Cu")
		(at 314.861448 -120.476772 180)
		(property "Reference" "C452"
			(at 0 0 180)
			(layer "F.SilkS")
			(hide yes)
			(effects
				(font
					(size 1.27 1.27)
				)
			)
		)
		(property "Value" ""
			(at 0 0 180)
			(layer "F.Fab")
			(effects
				(font
					(size 1.27 1.27)
				)
			)
		)
		(duplicate_pad_numbers_are_jumpers no)
		(fp_line
			(start 0.299974 0.150114)
			(end -0.299974 0.150114)
			(stroke
				(width 0.1)
				(type default)
			)
			(layer "F.Fab")
		)
		(fp_line
			(start 0.299974 -0.150114)
			(end 0.299974 0.150114)
			(stroke
				(width 0.1)
				(type default)
			)
			(layer "F.Fab")
		)
		(fp_line
			(start -0.299974 0.150114)
			(end -0.299974 -0.150114)
			(stroke
				(width 0.1)
				(type default)
			)
			(layer "F.Fab")
		)
		(fp_line
			(start -0.299974 -0.150114)
			(end 0.299974 -0.150114)
			(stroke
				(width 0.1)
				(type default)
			)
			(layer "F.Fab")
		)
		(pad "1" smd rect
			(at -0.2667 0 180)
			(size 0.3048 0.381)
			(layers "F.Cu" "F.Mask" "F.Paste")
			(net "P5E_PEX2_STN0_TX_DN<1>")
		)
		(pad "2" smd rect
			(at 0.2667 0 180)
			(size 0.3048 0.381)
			(layers "F.Cu" "F.Mask" "F.Paste")
			(net "P5E_PEX2_STN0_TX_C_DN<1>")
		)
	)
	(footprint ""
		(layer "F.Cu")
		(at 214.73033 -235.756958 90)
		(property "Reference" "R6359"
			(at 0 0 90)
			(layer "F.SilkS")
			(hide yes)
			(effects
				(font
					(size 1.27 1.27)
				)
			)
		)
		(property "Value" ""
			(at 0 0 90)
			(layer "F.Fab")
			(effects
				(font
					(size 1.27 1.27)
				)
			)
		)
		(duplicate_pad_numbers_are_jumpers no)
		(fp_line
			(start 0.7874 -0.4064)
			(end 0.7874 0.4064)
			(stroke
				(width 0.1524)
				(type default)
			)
			(layer "F.SilkS")
		)
		(fp_line
			(start -0.7874 -0.4064)
			(end 0.7874 -0.4064)
			(stroke
				(width 0.1524)
				(type default)
			)
			(layer "F.SilkS")
		)
		(fp_line
			(start 0.7874 0.4064)
			(end -0.7874 0.4064)
			(stroke
				(width 0.1524)
				(type default)
			)
			(layer "F.SilkS")
		)
		(fp_line
			(start -0.7874 0.4064)
			(end -0.7874 -0.4064)
			(stroke
				(width 0.1524)
				(type default)
			)
			(layer "F.SilkS")
		)
		(fp_line
			(start -0.12065 -0.305054)
			(end -0.12065 -0.2794)
			(stroke
				(width 0.1)
				(type default)
			)
			(layer "F.Fab")
		)
		(fp_line
			(start -0.67945 -0.305054)
			(end -0.12065 -0.305054)
			(stroke
				(width 0.1)
				(type default)
			)
			(layer "F.Fab")
		)
		(fp_line
			(start 0.67945 -0.3048)
			(end 0.67945 0.3048)
			(stroke
				(width 0.1)
				(type default)
			)
			(layer "F.Fab")
		)
		(fp_line
			(start 0.12065 -0.3048)
			(end 0.67945 -0.3048)
			(stroke
				(width 0.1)
				(type default)
			)
			(layer "F.Fab")
		)
		(fp_line
			(start 0.12065 -0.2794)
			(end 0.12065 -0.3048)
			(stroke
				(width 0.1)
				(type default)
			)
			(layer "F.Fab")
		)
		(fp_line
			(start -0.12065 -0.2794)
			(end 0.12065 -0.2794)
			(stroke
				(width 0.1)
				(type default)
			)
			(layer "F.Fab")
		)
		(fp_line
			(start 0.120396 0.2794)
			(end -0.12065 0.2794)
			(stroke
				(width 0.1)
				(type default)
			)
			(layer "F.Fab")
		)
		(fp_line
			(start -0.12065 0.2794)
			(end -0.12065 0.3048)
			(stroke
				(width 0.1)
				(type default)
			)
			(layer "F.Fab")
		)
		(fp_line
			(start 0.67945 0.3048)
			(end 0.120396 0.3048)
			(stroke
				(width 0.1)
				(type default)
			)
			(layer "F.Fab")
		)
		(fp_line
			(start 0.120396 0.3048)
			(end 0.120396 0.2794)
			(stroke
				(width 0.1)
				(type default)
			)
			(layer "F.Fab")
		)
		(fp_line
			(start -0.12065 0.3048)
			(end -0.67945 0.3048)
			(stroke
				(width 0.1)
				(type default)
			)
			(layer "F.Fab")
		)
		(fp_line
			(start -0.67945 0.3048)
			(end -0.67945 -0.305054)
			(stroke
				(width 0.1)
				(type default)
			)
			(layer "F.Fab")
		)
		(pad "1" smd circle
			(at -0.40005 0 90)
			(size 0 0)
			(layers "F.Cu" "F.Mask" "F.Paste")
			(net "SMB_PEX_LS_R_SDA")
		)
		(pad "2" smd circle
			(at 0.40005 0 90)
			(size 0 0)
			(layers "F.Cu" "F.Mask" "F.Paste")
			(net "SMB_PEX_LS_SDA")
		)
	)
	(footprint ""
		(layer "F.Cu")
		(at 321.20205 -306.074572 90)
		(property "Reference" "R1370"
			(at 0 0 90)
			(layer "F.SilkS")
			(hide yes)
			(effects
				(font
					(size 1.27 1.27)
				)
			)
		)
		(property "Value" ""
			(at 0 0 90)
			(layer "F.Fab")
			(effects
				(font
					(size 1.27 1.27)
				)
			)
		)
		(duplicate_pad_numbers_are_jumpers no)
		(fp_line
			(start 0.7874 -0.4064)
			(end 0.7874 0.4064)
			(stroke
				(width 0.1524)
				(type default)
			)
			(layer "F.SilkS")
		)
		(fp_line
			(start -0.7874 -0.4064)
			(end 0.7874 -0.4064)
			(stroke
				(width 0.1524)
				(type default)
			)
			(layer "F.SilkS")
		)
		(fp_line
			(start 0.7874 0.4064)
			(end -0.7874 0.4064)
			(stroke
				(width 0.1524)
				(type default)
			)
			(layer "F.SilkS")
		)
		(fp_line
			(start -0.7874 0.4064)
			(end -0.7874 -0.4064)
			(stroke
				(width 0.1524)
				(type default)
			)
			(layer "F.SilkS")
		)
		(fp_line
			(start -0.12065 -0.305054)
			(end -0.12065 -0.2794)
			(stroke
				(width 0.1)
				(type default)
			)
			(layer "F.Fab")
		)
		(fp_line
			(start -0.67945 -0.305054)
			(end -0.12065 -0.305054)
			(stroke
				(width 0.1)
				(type default)
			)
			(layer "F.Fab")
		)
		(fp_line
			(start 0.67945 -0.3048)
			(end 0.67945 0.3048)
			(stroke
				(width 0.1)
				(type default)
			)
			(layer "F.Fab")
		)
		(fp_line
			(start 0.12065 -0.3048)
			(end 0.67945 -0.3048)
			(stroke
				(width 0.1)
				(type default)
			)
			(layer "F.Fab")
		)
		(fp_line
			(start 0.12065 -0.2794)
			(end 0.12065 -0.3048)
			(stroke
				(width 0.1)
				(type default)
			)
			(layer "F.Fab")
		)
		(fp_line
			(start -0.12065 -0.2794)
			(end 0.12065 -0.2794)
			(stroke
				(width 0.1)
				(type default)
			)
			(layer "F.Fab")
		)
		(fp_line
			(start 0.120396 0.2794)
			(end -0.12065 0.2794)
			(stroke
				(width 0.1)
				(type default)
			)
			(layer "F.Fab")
		)
		(fp_line
			(start -0.12065 0.2794)
			(end -0.12065 0.3048)
			(stroke
				(width 0.1)
				(type default)
			)
			(layer "F.Fab")
		)
		(fp_line
			(start 0.67945 0.3048)
			(end 0.120396 0.3048)
			(stroke
				(width 0.1)
				(type default)
			)
			(layer "F.Fab")
		)
		(fp_line
			(start 0.120396 0.3048)
			(end 0.120396 0.2794)
			(stroke
				(width 0.1)
				(type default)
			)
			(layer "F.Fab")
		)
		(fp_line
			(start -0.12065 0.3048)
			(end -0.67945 0.3048)
			(stroke
				(width 0.1)
				(type default)
			)
			(layer "F.Fab")
		)
		(fp_line
			(start -0.67945 0.3048)
			(end -0.67945 -0.305054)
			(stroke
				(width 0.1)
				(type default)
			)
			(layer "F.Fab")
		)
		(pad "1" smd circle
			(at -0.40005 0 90)
			(size 0 0)
			(layers "F.Cu" "F.Mask" "F.Paste")
			(net "PEX2_SPARE4")
		)
		(pad "2" smd circle
			(at 0.40005 0 90)
			(size 0 0)
			(layers "F.Cu" "F.Mask" "F.Paste")
			(net "P1V8_PEX")
		)
	)
	(footprint ""
		(layer "F.Cu")
		(at 275.871432 -387.352032 -90)
		(property "Reference" "PC6604"
			(at 0 0 270)
			(layer "F.SilkS")
			(hide yes)
			(effects
				(font
					(size 1.27 1.27)
				)
			)
		)
		(property "Value" ""
			(at 0 0 270)
			(layer "F.Fab")
			(effects
				(font
					(size 1.27 1.27)
				)
			)
		)
		(duplicate_pad_numbers_are_jumpers no)
		(fp_line
			(start -0.7874 0.4064)
			(end -0.7874 -0.4064)
			(stroke
				(width 0.1524)
				(type default)
			)
			(layer "F.SilkS")
		)
		(fp_line
			(start 0.7874 0.4064)
			(end -0.7874 0.4064)
			(stroke
				(width 0.1524)
				(type default)
			)
			(layer "F.SilkS")
		)
		(fp_line
			(start -0.7874 -0.4064)
			(end 0.7874 -0.4064)
			(stroke
				(width 0.1524)
				(type default)
			)
			(layer "F.SilkS")
		)
		(fp_line
			(start 0.7874 -0.4064)
			(end 0.7874 0.4064)
			(stroke
				(width 0.1524)
				(type default)
			)
			(layer "F.SilkS")
		)
		(fp_line
			(start -0.67945 0.3048)
			(end -0.67945 -0.305054)
			(stroke
				(width 0.1)
				(type default)
			)
			(layer "F.Fab")
		)
		(fp_line
			(start -0.12065 0.3048)
			(end -0.67945 0.3048)
			(stroke
				(width 0.1)
				(type default)
			)
			(layer "F.Fab")
		)
		(fp_line
			(start 0.120396 0.3048)
			(end 0.120396 0.2794)
			(stroke
				(width 0.1)
				(type default)
			)
			(layer "F.Fab")
		)
		(fp_line
			(start 0.67945 0.3048)
			(end 0.120396 0.3048)
			(stroke
				(width 0.1)
				(type default)
			)
			(layer "F.Fab")
		)
		(fp_line
			(start -0.12065 0.2794)
			(end -0.12065 0.3048)
			(stroke
				(width 0.1)
				(type default)
			)
			(layer "F.Fab")
		)
		(fp_line
			(start 0.120396 0.2794)
			(end -0.12065 0.2794)
			(stroke
				(width 0.1)
				(type default)
			)
			(layer "F.Fab")
		)
		(fp_line
			(start -0.12065 -0.2794)
			(end 0.12065 -0.2794)
			(stroke
				(width 0.1)
				(type default)
			)
			(layer "F.Fab")
		)
		(fp_line
			(start 0.12065 -0.2794)
			(end 0.12065 -0.3048)
			(stroke
				(width 0.1)
				(type default)
			)
			(layer "F.Fab")
		)
		(fp_line
			(start 0.12065 -0.3048)
			(end 0.67945 -0.3048)
			(stroke
				(width 0.1)
				(type default)
			)
			(layer "F.Fab")
		)
		(fp_line
			(start 0.67945 -0.3048)
			(end 0.67945 0.3048)
			(stroke
				(width 0.1)
				(type default)
			)
			(layer "F.Fab")
		)
		(fp_line
			(start -0.67945 -0.305054)
			(end -0.12065 -0.305054)
			(stroke
				(width 0.1)
				(type default)
			)
			(layer "F.Fab")
		)
		(fp_line
			(start -0.12065 -0.305054)
			(end -0.12065 -0.2794)
			(stroke
				(width 0.1)
				(type default)
			)
			(layer "F.Fab")
		)
		(pad "1" smd circle
			(at -0.40005 0 270)
			(size 0 0)
			(layers "F.Cu" "F.Mask" "F.Paste")
			(net "P3V3_AUX")
		)
		(pad "2" smd circle
			(at 0.40005 0 270)
			(size 0 0)
			(layers "F.Cu" "F.Mask" "F.Paste")
			(net "GND")
		)
	)
	(footprint ""
		(layer "F.Cu")
		(at 239.813338 -134.042404)
		(property "Reference" "R4445"
			(at 0 0 0)
			(layer "F.SilkS")
			(hide yes)
			(effects
				(font
					(size 1.27 1.27)
				)
			)
		)
		(property "Value" ""
			(at 0 0 0)
			(layer "F.Fab")
			(effects
				(font
					(size 1.27 1.27)
				)
			)
		)
		(duplicate_pad_numbers_are_jumpers no)
		(fp_line
			(start -0.7874 -0.4064)
			(end 0.7874 -0.4064)
			(stroke
				(width 0.1524)
				(type default)
			)
			(layer "F.SilkS")
		)
		(fp_line
			(start -0.7874 0.4064)
			(end -0.7874 -0.4064)
			(stroke
				(width 0.1524)
				(type default)
			)
			(layer "F.SilkS")
		)
		(fp_line
			(start 0.7874 -0.4064)
			(end 0.7874 0.4064)
			(stroke
				(width 0.1524)
				(type default)
			)
			(layer "F.SilkS")
		)
		(fp_line
			(start 0.7874 0.4064)
			(end -0.7874 0.4064)
			(stroke
				(width 0.1524)
				(type default)
			)
			(layer "F.SilkS")
		)
		(fp_line
			(start -0.67945 -0.305054)
			(end -0.12065 -0.305054)
			(stroke
				(width 0.1)
				(type default)
			)
			(layer "F.Fab")
		)
		(fp_line
			(start -0.67945 0.3048)
			(end -0.67945 -0.305054)
			(stroke
				(width 0.1)
				(type default)
			)
			(layer "F.Fab")
		)
		(fp_line
			(start -0.12065 -0.305054)
			(end -0.12065 -0.2794)
			(stroke
				(width 0.1)
				(type default)
			)
			(layer "F.Fab")
		)
		(fp_line
			(start -0.12065 -0.2794)
			(end 0.12065 -0.2794)
			(stroke
				(width 0.1)
				(type default)
			)
			(layer "F.Fab")
		)
		(fp_line
			(start -0.12065 0.2794)
			(end -0.12065 0.3048)
			(stroke
				(width 0.1)
				(type default)
			)
			(layer "F.Fab")
		)
		(fp_line
			(start -0.12065 0.3048)
			(end -0.67945 0.3048)
			(stroke
				(width 0.1)
				(type default)
			)
			(layer "F.Fab")
		)
		(fp_line
			(start 0.120396 0.2794)
			(end -0.12065 0.2794)
			(stroke
				(width 0.1)
				(type default)
			)
			(layer "F.Fab")
		)
		(fp_line
			(start 0.120396 0.3048)
			(end 0.120396 0.2794)
			(stroke
				(width 0.1)
				(type default)
			)
			(layer "F.Fab")
		)
		(fp_line
			(start 0.12065 -0.3048)
			(end 0.67945 -0.3048)
			(stroke
				(width 0.1)
				(type default)
			)
			(layer "F.Fab")
		)
		(fp_line
			(start 0.12065 -0.2794)
			(end 0.12065 -0.3048)
			(stroke
				(width 0.1)
				(type default)
			)
			(layer "F.Fab")
		)
		(fp_line
			(start 0.67945 -0.3048)
			(end 0.67945 0.3048)
			(stroke
				(width 0.1)
				(type default)
			)
			(layer "F.Fab")
		)
		(fp_line
			(start 0.67945 0.3048)
			(end 0.120396 0.3048)
			(stroke
				(width 0.1)
				(type default)
			)
			(layer "F.Fab")
		)
		(pad "1" smd circle
			(at -0.40005 0)
			(size 0 0)
			(layers "F.Cu" "F.Mask" "F.Paste")
			(net "HP_NIC4_EN")
		)
		(pad "2" smd circle
			(at 0.40005 0)
			(size 0 0)
			(layers "F.Cu" "F.Mask" "F.Paste")
			(net "P12V_NIC4_EN_R")
		)
	)
)
